FILE_TYPE = CONNECTIVITY;
{Allegro Design Entry HDL 17.2-2016 S081 (4005846) 1/11/2022}
"PAGE_NUMBER" = 213;
0"NC";
END.
